# BASEBOARD_FAB2 (Tioga Pass) — schematic netlist excerpt (pin names and nets, part order shuffled) for the footprints in the layout excerpt that follows; sources: Cadence DE-HDL packaged netlist, KiCad conversion of Wiwynn_Tioga_Pass_MB.brd

R2R5  RES  1.00K 1% CHIP  pkg 0402  page 133 : A = P3V3_STBY ; B = FM_PCH_PLD_DATA
C1A10  CAP_A  0.1UF 16V 10% X7R  pkg 0402V  page 227 : A = VR_FET_SW_P12V_STBY_PVDDQ_KLM ; B = GND
R3D28  RES  100.0 1% CHIP  pkg 0402  page 214 : A = VSENSE_PVCCIO_CPU1_AVSN ; B = GND

(kicad_pcb
	(version 20260206)
	(generator "pcbnew")
	(generator_version "10.0")
	(general
		(thickness 1.6)
		(legacy_teardrops no)
	)
	(paper "A4")
	(title_block
		(title "Wiwynn_Tioga_Pass_MB.brd")
		(comment 1 "Tioga Pass / footprints 1855-1857 of 4770")
	)
	(layers
		(0 "F.Cu" signal "TOP")
		(4 "In1.Cu" signal "L2GND")
		(6 "In2.Cu" signal "L3")
		(8 "In3.Cu" signal "L4GND")
		(10 "In4.Cu" signal "L5")
		(12 "In5.Cu" signal "L6GND")
		(14 "In6.Cu" signal "L7VCC")
		(16 "In7.Cu" signal "L8VCC")
		(18 "In8.Cu" signal "L9GND")
		(20 "In9.Cu" signal "L10")
		(22 "In10.Cu" signal "L11GND")
		(24 "In11.Cu" signal "L12")
		(26 "In12.Cu" signal "L13GND")
		(2 "B.Cu" signal "BOTTOM")
		(9 "F.Adhes" user "F.Adhesive")
		(11 "B.Adhes" user "B.Adhesive")
		(13 "F.Paste" user "Package Geometry/Pastemask Top")
		(15 "B.Paste" user "Package Geometry/Pastemask Bottom")
		(5 "F.SilkS" user "Ref Des/Silkscreen Top")
		(7 "B.SilkS" user "Ref Des/Silkscreen Bottom")
		(1 "F.Mask" user "Board Geometry/Soldermask Top")
		(3 "B.Mask" user "Board Geometry/Soldermask Bottom")
		(17 "Dwgs.User" user "User.Drawings")
		(19 "Cmts.User" user "User.Comments")
		(21 "Eco1.User" user "User.Eco1")
		(23 "Eco2.User" user "User.Eco2")
		(25 "Edge.Cuts" user "Board Geometry/Outline")
		(27 "Margin" user)
		(31 "F.CrtYd" user "Package Geometry/Place Bound Top")
		(29 "B.CrtYd" user "Package Geometry/Place Bound Bottom")
		(35 "F.Fab" user "Ref Des/Assembly Top")
		(33 "B.Fab" user "Ref Des/Assembly Bottom")
	)
	(footprint ""
		(layer "F.Cu")
		(at 162.6362 -66.675 -90)
		(property "Reference" "R3D28"
			(at 0 0 270)
			(layer "F.SilkS")
			(hide yes)
			(effects
				(font
					(size 1.27 1.27)
				)
			)
		)
		(property "Value" ""
			(at 0 0 270)
			(layer "F.Fab")
			(effects
				(font
					(size 1.27 1.27)
				)
			)
		)
		(duplicate_pad_numbers_are_jumpers no)
		(fp_poly
			(pts
				(xy -0.2794 -0.1016) (xy 0.2794 -0.1016) (xy 0.2794 0.9906) (xy -0.2794 0.9906)
			)
			(stroke
				(width 0)
				(type default)
			)
			(fill no)
			(layer "F.CrtYd")
		)
		(fp_line
			(start -0.2794 0.9906)
			(end 0.2794 0.9906)
			(stroke
				(width 0.1)
				(type default)
			)
			(layer "F.Fab")
		)
		(fp_line
			(start 0.2794 0.9906)
			(end 0.2794 -0.1016)
			(stroke
				(width 0.1)
				(type default)
			)
			(layer "F.Fab")
		)
		(fp_line
			(start -0.2794 -0.1016)
			(end -0.2794 0.9906)
			(stroke
				(width 0.1)
				(type default)
			)
			(layer "F.Fab")
		)
		(fp_line
			(start 0.2794 -0.1016)
			(end -0.2794 -0.1016)
			(stroke
				(width 0.1)
				(type default)
			)
			(layer "F.Fab")
		)
		(pad "1" smd rect
			(at 0 0 270)
			(size 0.508 0.508)
			(layers "F.Cu" "F.Mask" "F.Paste")
			(net "VSENSE_PVCCIO_CPU1_AVSN")
		)
		(pad "2" smd rect
			(at 0 0.889 270)
			(size 0.508 0.508)
			(layers "F.Cu" "F.Mask" "F.Paste")
			(net "GND")
		)
		(zone
			(layer "F.Cu")
			(hatch none 0.5)
			(connect_pads
				(clearance 0)
			)
			(min_thickness 0.25)
			(keepout
				(tracks not_allowed)
				(vias allowed)
				(pads allowed)
				(copperpour not_allowed)
				(footprints allowed)
			)
			(placement
				(enabled no)
				(sheetname "")
			)
			(fill
				(thermal_gap 0.5)
				(thermal_bridge_width 0.5)
				(island_removal_mode 0)
			)
			(polygon
				(pts
					(xy 162.0012 -66.929) (xy 162.0012 -66.421) (xy 162.3822 -66.421) (xy 162.3822 -66.929)
				)
			)
		)
		(zone
			(layer "F.Cu")
			(hatch none 0.5)
			(connect_pads
				(clearance 0)
			)
			(min_thickness 0.25)
			(keepout
				(tracks allowed)
				(vias not_allowed)
				(pads allowed)
				(copperpour not_allowed)
				(footprints allowed)
			)
			(placement
				(enabled no)
				(sheetname "")
			)
			(fill
				(thermal_gap 0.5)
				(thermal_bridge_width 0.5)
				(island_removal_mode 0)
			)
			(polygon
				(pts
					(xy 162.3822 -66.929) (xy 162.3822 -66.421) (xy 162.0012 -66.421) (xy 162.0012 -66.929)
				)
			)
		)
	)
	(footprint ""
		(layer "F.Cu")
		(at 412.4325 -110.617 90)
		(property "Reference" "R2R5"
			(at 0 0 90)
			(layer "F.SilkS")
			(hide yes)
			(effects
				(font
					(size 1.27 1.27)
				)
			)
		)
		(property "Value" ""
			(at 0 0 90)
			(layer "F.Fab")
			(effects
				(font
					(size 1.27 1.27)
				)
			)
		)
		(duplicate_pad_numbers_are_jumpers no)
		(fp_poly
			(pts
				(xy -0.2794 -0.1016) (xy 0.2794 -0.1016) (xy 0.2794 0.9906) (xy -0.2794 0.9906)
			)
			(stroke
				(width 0)
				(type default)
			)
			(fill no)
			(layer "F.CrtYd")
		)
		(fp_line
			(start 0.2794 -0.1016)
			(end -0.2794 -0.1016)
			(stroke
				(width 0.1)
				(type default)
			)
			(layer "F.Fab")
		)
		(fp_line
			(start -0.2794 -0.1016)
			(end -0.2794 0.9906)
			(stroke
				(width 0.1)
				(type default)
			)
			(layer "F.Fab")
		)
		(fp_line
			(start 0.2794 0.9906)
			(end 0.2794 -0.1016)
			(stroke
				(width 0.1)
				(type default)
			)
			(layer "F.Fab")
		)
		(fp_line
			(start -0.2794 0.9906)
			(end 0.2794 0.9906)
			(stroke
				(width 0.1)
				(type default)
			)
			(layer "F.Fab")
		)
		(pad "1" smd rect
			(at 0 0 90)
			(size 0.508 0.508)
			(layers "F.Cu" "F.Mask" "F.Paste")
			(net "P3V3_STBY")
		)
		(pad "2" smd rect
			(at 0 0.889 90)
			(size 0.508 0.508)
			(layers "F.Cu" "F.Mask" "F.Paste")
			(net "FM_PCH_PLD_DATA")
		)
		(zone
			(layer "F.Cu")
			(hatch none 0.5)
			(connect_pads
				(clearance 0)
			)
			(min_thickness 0.25)
			(keepout
				(tracks allowed)
				(vias not_allowed)
				(pads allowed)
				(copperpour not_allowed)
				(footprints allowed)
			)
			(placement
				(enabled no)
				(sheetname "")
			)
			(fill
				(thermal_gap 0.5)
				(thermal_bridge_width 0.5)
				(island_removal_mode 0)
			)
			(polygon
				(pts
					(xy 412.6865 -110.363) (xy 412.6865 -110.871) (xy 413.0675 -110.871) (xy 413.0675 -110.363)
				)
			)
		)
		(zone
			(layer "F.Cu")
			(hatch none 0.5)
			(connect_pads
				(clearance 0)
			)
			(min_thickness 0.25)
			(keepout
				(tracks not_allowed)
				(vias allowed)
				(pads allowed)
				(copperpour not_allowed)
				(footprints allowed)
			)
			(placement
				(enabled no)
				(sheetname "")
			)
			(fill
				(thermal_gap 0.5)
				(thermal_bridge_width 0.5)
				(island_removal_mode 0)
			)
			(polygon
				(pts
					(xy 413.0675 -110.363) (xy 413.0675 -110.871) (xy 412.6865 -110.871) (xy 412.6865 -110.363)
				)
			)
		)
	)
	(footprint ""
		(layer "F.Cu")
		(at 1.84912 -142.002256 90)
		(property "Reference" "C1A10"
			(at 0 0 90)
			(layer "F.SilkS")
			(hide yes)
			(effects
				(font
					(size 1.27 1.27)
				)
			)
		)
		(property "Value" ""
			(at 0 0 90)
			(layer "F.Fab")
			(effects
				(font
					(size 1.27 1.27)
				)
			)
		)
		(duplicate_pad_numbers_are_jumpers no)
		(fp_rect
			(start 0.3048 -0.1016)
			(end -0.3048 0.9906)
			(stroke
				(width 0)
				(type default)
			)
			(fill no)
			(layer "F.CrtYd")
		)
		(fp_line
			(start 0.3048 -0.1016)
			(end -0.3048 -0.1016)
			(stroke
				(width 0.1)
				(type default)
			)
			(layer "F.Fab")
		)
		(fp_line
			(start -0.3048 -0.1016)
			(end -0.3048 0.9906)
			(stroke
				(width 0.1)
				(type default)
			)
			(layer "F.Fab")
		)
		(fp_line
			(start 0.3048 0.9906)
			(end 0.3048 -0.1016)
			(stroke
				(width 0.1)
				(type default)
			)
			(layer "F.Fab")
		)
		(fp_line
			(start -0.3048 0.9906)
			(end 0.3048 0.9906)
			(stroke
				(width 0.1)
				(type default)
			)
			(layer "F.Fab")
		)
		(pad "1" smd rect
			(at 0 0 90)
			(size 0.508 0.508)
			(layers "F.Cu" "F.Mask" "F.Paste")
			(net "VR_FET_SW_P12V_STBY_PVDDQ_KLM")
		)
		(pad "2" smd rect
			(at 0 0.889 90)
			(size 0.508 0.508)
			(layers "F.Cu" "F.Mask" "F.Paste")
			(net "GND")
		)
		(zone
			(layer "F.Cu")
			(hatch none 0.5)
			(connect_pads
				(clearance 0)
			)
			(min_thickness 0.25)
			(keepout
				(tracks not_allowed)
				(vias allowed)
				(pads allowed)
				(copperpour not_allowed)
				(footprints allowed)
			)
			(placement
				(enabled no)
				(sheetname "")
			)
			(fill
				(thermal_gap 0.5)
				(thermal_bridge_width 0.5)
				(island_removal_mode 0)
			)
			(polygon
				(pts
					(xy 2.10312 -142.256256) (xy 2.10312 -141.748256) (xy 2.48412 -141.748256) (xy 2.48412 -142.256256)
				)
			)
		)
		(zone
			(layer "F.Cu")
			(hatch none 0.5)
			(connect_pads
				(clearance 0)
			)
			(min_thickness 0.25)
			(keepout
				(tracks allowed)
				(vias not_allowed)
				(pads allowed)
				(copperpour not_allowed)
				(footprints allowed)
			)
			(placement
				(enabled no)
				(sheetname "")
			)
			(fill
				(thermal_gap 0.5)
				(thermal_bridge_width 0.5)
				(island_removal_mode 0)
			)
			(polygon
				(pts
					(xy 2.10312 -142.256256) (xy 2.10312 -141.748256) (xy 2.48412 -141.748256) (xy 2.48412 -142.256256)
				)
			)
		)
	)
)
